(kicad_pcb
	(version 20241229)
	(generator "pcbnew")
	(generator_version "9.0")
	(general
		(thickness 1.6)
		(legacy_teardrops no)
	)
	(paper "A4")
	(title_block
		(title "GMSL Deserializer")
		(date "2025-10-09")
		(rev "1.0.4")
		(company "Antmicro Ltd")
		(comment 1 "www.antmicro.com")
		(comment 9 "footprints 102-107 of 235")
	)
	(layers
		(0 "F.Cu" signal)
		(4 "In1.Cu" power)
		(6 "In2.Cu" power)
		(2 "B.Cu" signal)
		(9 "F.Adhes" user "F.Adhesive")
		(11 "B.Adhes" user "B.Adhesive")
		(13 "F.Paste" user)
		(15 "B.Paste" user)
		(5 "F.SilkS" user "F.Silkscreen")
		(7 "B.SilkS" user "B.Silkscreen")
		(1 "F.Mask" user)
		(3 "B.Mask" user)
		(17 "Dwgs.User" user "User.Drawings")
		(19 "Cmts.User" user "User.Comments")
		(21 "Eco1.User" user "User.Eco1")
		(23 "Eco2.User" user "User.Eco2")
		(25 "Edge.Cuts" user)
		(27 "Margin" user)
		(31 "F.CrtYd" user "F.Courtyard")
		(29 "B.CrtYd" user "B.Courtyard")
		(35 "F.Fab" user)
		(33 "B.Fab" user)
	)
	(footprint "antmicro-footprints:R_0402_1005Metric"
		(layer "F.Cu")
		(at 120.324 83.162 180)
		(descr "Resistor SMD 0402")
		(tags "resistor SMD 0402")
		(property "Reference" "R37"
			(at 1.016 0.358 0)
			(layer "F.SilkS")
			(effects
				(font
					(size 0.7 0.7)
					(thickness 0.15)
				)
				(justify right bottom)
			)
		)
		(property "Value" "R_4k99_0402"
			(at -1.011843 1.772047 0)
			(layer "F.Fab")
			(effects
				(font
					(size 0.7 0.7)
					(thickness 0.15)
				)
				(justify right bottom)
			)
		)
		(property "Datasheet" "https://www.bourns.com/docs/product-datasheets/cr.pdf"
			(at 0 0 180)
			(layer "F.Fab")
			(hide yes)
			(effects
				(font
					(size 1.27 1.27)
					(thickness 0.15)
				)
			)
		)
		(property "Description" "SMD Chip Resistor, 4.99 kohm, ± 1%, 62.5 mW, 0402 [1005 Metric], Thick Film, General Purpose"
			(at 0 0 180)
			(layer "F.Fab")
			(hide yes)
			(effects
				(font
					(size 1.27 1.27)
					(thickness 0.15)
				)
			)
		)
		(property "Author" "Antmicro"
			(at 240.648 166.324 0)
			(layer "F.Fab")
			(hide yes)
			(effects
				(font
					(size 1 1)
					(thickness 0.15)
				)
			)
		)
		(property "License" "Apache-2.0"
			(at 240.648 166.324 0)
			(layer "F.Fab")
			(hide yes)
			(effects
				(font
					(size 1 1)
					(thickness 0.15)
				)
			)
		)
		(property "MPN" "CR0402-FX-4991GLF"
			(at 240.648 166.324 0)
			(layer "F.Fab")
			(hide yes)
			(effects
				(font
					(size 1 1)
					(thickness 0.15)
				)
			)
		)
		(property "Manufacturer" "Bourns"
			(at 240.648 166.324 0)
			(layer "F.Fab")
			(hide yes)
			(effects
				(font
					(size 1 1)
					(thickness 0.15)
				)
			)
		)
		(property "Tolerance" "1%"
			(at 240.648 166.324 0)
			(layer "F.Fab")
			(hide yes)
			(effects
				(font
					(size 1 1)
					(thickness 0.15)
				)
			)
		)
		(property "Val" "4k99"
			(at 240.648 166.324 0)
			(layer "F.Fab")
			(hide yes)
			(effects
				(font
					(size 1 1)
					(thickness 0.15)
				)
			)
		)
		(sheetname "/Power/")
		(sheetfile "power.kicad_sch")
		(attr smd)
		(fp_rect
			(start -0.925 -0.47)
			(end 0.925 0.47)
			(stroke
				(width 0.05)
				(type default)
			)
			(fill no)
			(layer "F.CrtYd")
		)
		(fp_rect
			(start -0.5 -0.25)
			(end 0.5 0.25)
			(stroke
				(width 0.15)
				(type solid)
			)
			(fill no)
			(layer "F.Fab")
		)
		(pad "1" smd roundrect
			(at -0.48 0 180)
			(size 0.59 0.64)
			(layers "F.Cu" "F.Mask" "F.Paste")
			(roundrect_rratio 0.25)
			(net 71 "/Power/FB_1V2")
			(pintype "passive")
		)
		(pad "2" smd roundrect
			(at 0.48 0 180)
			(size 0.59 0.64)
			(layers "F.Cu" "F.Mask" "F.Paste")
			(roundrect_rratio 0.25)
			(net 11 "/Power/OUT_1V2")
			(pintype "passive")
		)
	)
	(footprint "antmicro-footprints:C_0402_1005Metric"
		(layer "F.Cu")
		(at 171.45 50.5)
		(descr "Capacitor SMD 0402")
		(tags "capacitor SMD 0402")
		(property "Reference" "C2"
			(at 0.381547 -0.600406 0)
			(layer "F.SilkS")
			(effects
				(font
					(size 0.7 0.7)
					(thickness 0.15)
				)
				(justify right bottom)
			)
		)
		(property "Value" "C_100n_0402"
			(at -1.022927 2.155213 0)
			(layer "F.Fab")
			(effects
				(font
					(size 0.7 0.7)
					(thickness 0.15)
				)
				(justify left bottom)
			)
		)
		(property "Datasheet" "https://www.murata.com/products/productdetail?partno=GRM155R61H104KE14%23"
			(at 0 0 0)
			(layer "F.Fab")
			(hide yes)
			(effects
				(font
					(size 1.27 1.27)
					(thickness 0.15)
				)
			)
		)
		(property "Description" "SMD Multilayer Ceramic Capacitor, 0.1 µF, 50 V, 0402 [1005 Metric], ± 10%, X5R, GRM Series"
			(at 0 0 0)
			(layer "F.Fab")
			(hide yes)
			(effects
				(font
					(size 1.27 1.27)
					(thickness 0.15)
				)
			)
		)
		(property "Author" "Antmicro"
			(at 0 0 0)
			(layer "F.Fab")
			(hide yes)
			(effects
				(font
					(size 1 1)
					(thickness 0.15)
				)
			)
		)
		(property "Dielectric" "X5R"
			(at 0 0 0)
			(layer "F.Fab")
			(hide yes)
			(effects
				(font
					(size 1 1)
					(thickness 0.15)
				)
			)
		)
		(property "License" "Apache-2.0"
			(at 0 0 0)
			(layer "F.Fab")
			(hide yes)
			(effects
				(font
					(size 1 1)
					(thickness 0.15)
				)
			)
		)
		(property "MPN" "GRM155R61H104KE14D"
			(at 0 0 0)
			(layer "F.Fab")
			(hide yes)
			(effects
				(font
					(size 1 1)
					(thickness 0.15)
				)
			)
		)
		(property "Manufacturer" "Murata"
			(at 0 0 0)
			(layer "F.Fab")
			(hide yes)
			(effects
				(font
					(size 1 1)
					(thickness 0.15)
				)
			)
		)
		(property "Val" "100n"
			(at 0 0 0)
			(layer "F.Fab")
			(hide yes)
			(effects
				(font
					(size 1 1)
					(thickness 0.15)
				)
			)
		)
		(property "Voltage" "50V"
			(at 0 0 0)
			(layer "F.Fab")
			(hide yes)
			(effects
				(font
					(size 1 1)
					(thickness 0.15)
				)
			)
		)
		(sheetname "/Connectors/")
		(sheetfile "connectors.kicad_sch")
		(attr smd)
		(fp_rect
			(start -0.925 -0.47)
			(end 0.925 0.47)
			(stroke
				(width 0.05)
				(type default)
			)
			(fill no)
			(layer "F.CrtYd")
		)
		(fp_line
			(start -0.494 -0.25)
			(end 0.504 -0.25)
			(stroke
				(width 0.15)
				(type solid)
			)
			(layer "F.Fab")
		)
		(fp_line
			(start -0.494 0.248)
			(end -0.494 -0.25)
			(stroke
				(width 0.15)
				(type solid)
			)
			(layer "F.Fab")
		)
		(fp_line
			(start 0.504 -0.25)
			(end 0.504 0.248)
			(stroke
				(width 0.15)
				(type solid)
			)
			(layer "F.Fab")
		)
		(fp_line
			(start 0.504 0.248)
			(end -0.494 0.248)
			(stroke
				(width 0.15)
				(type solid)
			)
			(layer "F.Fab")
		)
		(pad "1" smd roundrect
			(at -0.48 0)
			(size 0.59 0.64)
			(layers "F.Cu" "F.Mask" "F.Paste")
			(roundrect_rratio 0.25)
			(net 1 "GND")
			(pintype "passive")
		)
		(pad "2" smd roundrect
			(at 0.48 0)
			(size 0.59 0.64)
			(layers "F.Cu" "F.Mask" "F.Paste")
			(roundrect_rratio 0.25)
			(net 2 "/Connectors/DC_UNFUSED")
			(pintype "passive")
		)
	)
	(footprint "antmicro-footprints:R_0402_1005Metric"
		(layer "F.Cu")
		(at 181.356 64.008)
		(descr "Resistor SMD 0402")
		(tags "resistor SMD 0402")
		(property "Reference" "R14"
			(at -1.27 9.2202 0)
			(layer "F.SilkS")
			(effects
				(font
					(size 0.7 0.7)
					(thickness 0.15)
				)
				(justify left bottom)
			)
		)
		(property "Value" "R_100R_0402"
			(at -1.011843 1.772047 0)
			(layer "F.Fab")
			(effects
				(font
					(size 0.7 0.7)
					(thickness 0.15)
				)
				(justify left bottom)
			)
		)
		(property "Datasheet" "https://www.bourns.com/docs/product-datasheets/cr.pdf"
			(at 0 0 0)
			(layer "F.Fab")
			(hide yes)
			(effects
				(font
					(size 1.27 1.27)
					(thickness 0.15)
				)
			)
		)
		(property "Description" "SMD Chip Resistor, 100 ohm, ± 1%, 62.5 mW, 0402 [1005 Metric], Thick Film, General Purpose"
			(at 0 0 0)
			(layer "F.Fab")
			(hide yes)
			(effects
				(font
					(size 1.27 1.27)
					(thickness 0.15)
				)
			)
		)
		(property "Author" "Antmicro"
			(at 0 0 0)
			(layer "F.Fab")
			(hide yes)
			(effects
				(font
					(size 1 1)
					(thickness 0.15)
				)
			)
		)
		(property "License" "Apache-2.0"
			(at 0 0 0)
			(layer "F.Fab")
			(hide yes)
			(effects
				(font
					(size 1 1)
					(thickness 0.15)
				)
			)
		)
		(property "MPN" "CR0402-FX-1000GLF"
			(at 0 0 0)
			(layer "F.Fab")
			(hide yes)
			(effects
				(font
					(size 1 1)
					(thickness 0.15)
				)
			)
		)
		(property "Manufacturer" "Bourns"
			(at 0 0 0)
			(layer "F.Fab")
			(hide yes)
			(effects
				(font
					(size 1 1)
					(thickness 0.15)
				)
			)
		)
		(property "Tolerance" "1%"
			(at 0 0 0)
			(layer "F.Fab")
			(hide yes)
			(effects
				(font
					(size 1 1)
					(thickness 0.15)
				)
			)
		)
		(property "Val" "100R"
			(at 0 0 0)
			(layer "F.Fab")
			(hide yes)
			(effects
				(font
					(size 1 1)
					(thickness 0.15)
				)
			)
		)
		(sheetname "/Connectors/")
		(sheetfile "connectors.kicad_sch")
		(attr smd)
		(fp_rect
			(start -0.925 -0.47)
			(end 0.925 0.47)
			(stroke
				(width 0.05)
				(type default)
			)
			(fill no)
			(layer "F.CrtYd")
		)
		(fp_rect
			(start -0.5 -0.25)
			(end 0.5 0.25)
			(stroke
				(width 0.15)
				(type solid)
			)
			(fill no)
			(layer "F.Fab")
		)
		(pad "1" smd roundrect
			(at -0.48 0)
			(size 0.59 0.64)
			(layers "F.Cu" "F.Mask" "F.Paste")
			(roundrect_rratio 0.25)
			(net 45 "/Connectors/SCL_CAM")
			(pintype "passive")
		)
		(pad "2" smd roundrect
			(at 0.48 0)
			(size 0.59 0.64)
			(layers "F.Cu" "F.Mask" "F.Paste")
			(roundrect_rratio 0.25)
			(net 43 "/Connectors/SCL_CAM1")
			(pintype "passive")
		)
	)
	(footprint "antmicro-footprints:L_Bourns-SRN8040"
		(layer "F.Cu")
		(at 120.578 73.764 -90)
		(property "Reference" "L17"
			(at -4.4728 4.3476 0)
			(layer "F.SilkS")
			(effects
				(font
					(size 0.7 0.7)
					(thickness 0.15)
				)
				(justify left bottom)
			)
		)
		(property "Value" "L_10u_3.1A_Bourns-SRN8040"
			(at 0 -5.461 90)
			(layer "F.Fab")
			(effects
				(font
					(size 0.7 0.7)
					(thickness 0.15)
				)
				(justify right bottom)
			)
		)
		(property "Datasheet" "https://www.bourns.com/pdfs/SRN8040.pdf"
			(at 0 0 270)
			(layer "F.Fab")
			(hide yes)
			(effects
				(font
					(size 1.27 1.27)
					(thickness 0.15)
				)
			)
		)
		(property "Description" "Power Inductor (SMD), 10 µH, 3.1 A, Shielded, 3.4 A, SRN8040"
			(at 0 0 270)
			(layer "F.Fab")
			(hide yes)
			(effects
				(font
					(size 1.27 1.27)
					(thickness 0.15)
				)
			)
		)
		(property "Author" "Antmicro"
			(at 46.814 194.342 0)
			(layer "F.Fab")
			(hide yes)
			(effects
				(font
					(size 1 1)
					(thickness 0.15)
				)
			)
		)
		(property "IMax" "3.1 A"
			(at 46.814 194.342 0)
			(layer "F.Fab")
			(hide yes)
			(effects
				(font
					(size 1 1)
					(thickness 0.15)
				)
			)
		)
		(property "ISat" "3.4 A"
			(at 46.814 194.342 0)
			(layer "F.Fab")
			(hide yes)
			(effects
				(font
					(size 1 1)
					(thickness 0.15)
				)
			)
		)
		(property "License" "Apache-2.0"
			(at 46.814 194.342 0)
			(layer "F.Fab")
			(hide yes)
			(effects
				(font
					(size 1 1)
					(thickness 0.15)
				)
			)
		)
		(property "MPN" "SRN8040-100M"
			(at 46.814 194.342 0)
			(layer "F.Fab")
			(hide yes)
			(effects
				(font
					(size 1 1)
					(thickness 0.15)
				)
			)
		)
		(property "Manufacturer" "Bourns"
			(at 46.814 194.342 0)
			(layer "F.Fab")
			(hide yes)
			(effects
				(font
					(size 1 1)
					(thickness 0.15)
				)
			)
		)
		(property "Size" "8.0x8.0"
			(at 46.814 194.342 0)
			(layer "F.Fab")
			(hide yes)
			(effects
				(font
					(size 1 1)
					(thickness 0.15)
				)
			)
		)
		(property "Val" "10u/3.1A"
			(at 46.814 194.342 0)
			(layer "F.Fab")
			(hide yes)
			(effects
				(font
					(size 1 1)
					(thickness 0.15)
				)
			)
		)
		(sheetname "/Power/")
		(sheetfile "power.kicad_sch")
		(attr smd)
		(fp_line
			(start -1.3 4.1)
			(end 1.3 4.1)
			(stroke
				(width 0.12)
				(type solid)
			)
			(layer "F.SilkS")
		)
		(fp_line
			(start -1.3 -4.1)
			(end 1.3 -4.1)
			(stroke
				(width 0.12)
				(type solid)
			)
			(layer "F.SilkS")
		)
		(fp_rect
			(start -4.325 -4.35)
			(end 4.325 4.35)
			(stroke
				(width 0.05)
				(type solid)
			)
			(fill no)
			(layer "F.CrtYd")
		)
		(fp_line
			(start -4.099 4.1)
			(end -4.099 -4.1)
			(stroke
				(width 0.15)
				(type solid)
			)
			(layer "F.Fab")
		)
		(fp_line
			(start 4.1 4.1)
			(end -4.099 4.1)
			(stroke
				(width 0.15)
				(type solid)
			)
			(layer "F.Fab")
		)
		(fp_line
			(start -4.099 -4.1)
			(end 4.1 -4.1)
			(stroke
				(width 0.15)
				(type solid)
			)
			(layer "F.Fab")
		)
		(fp_line
			(start 4.1 -4.1)
			(end 4.1 4.1)
			(stroke
				(width 0.15)
				(type solid)
			)
			(layer "F.Fab")
		)
		(pad "1" smd rect
			(at -2.8 0 270)
			(size 2.6 8.2)
			(layers "F.Cu" "F.Mask" "F.Paste")
			(net 5 "+5V")
			(pintype "passive")
		)
		(pad "2" smd rect
			(at 2.8 0 270)
			(size 2.6 8.2)
			(layers "F.Cu" "F.Mask" "F.Paste")
			(net 124 "/Power/SW_12V")
			(pintype "passive")
		)
	)
	(footprint "antmicro-footprints:R_0402_1005Metric"
		(layer "F.Cu")
		(at 139.192 93.472)
		(descr "Resistor SMD 0402")
		(tags "resistor SMD 0402")
		(property "Reference" "R32"
			(at 0.99 -0.508 0)
			(layer "F.SilkS")
			(effects
				(font
					(size 0.7 0.7)
					(thickness 0.15)
				)
				(justify left bottom)
			)
		)
		(property "Value" "R_10k_0402"
			(at -1.011843 1.772047 0)
			(layer "F.Fab")
			(effects
				(font
					(size 0.7 0.7)
					(thickness 0.15)
				)
				(justify left bottom)
			)
		)
		(property "Datasheet" "https://www.bourns.com/docs/product-datasheets/cr.pdf"
			(at 0 0 0)
			(layer "F.Fab")
			(hide yes)
			(effects
				(font
					(size 1.27 1.27)
					(thickness 0.15)
				)
			)
		)
		(property "Description" "SMD Chip Resistor, 10 kohm, ± 1%, 62.5 mW, 0402 [1005 Metric], Thick Film, General Purpose"
			(at 0 0 0)
			(layer "F.Fab")
			(hide yes)
			(effects
				(font
					(size 1.27 1.27)
					(thickness 0.15)
				)
			)
		)
		(property "Author" "Antmicro"
			(at 0 0 0)
			(layer "F.Fab")
			(hide yes)
			(effects
				(font
					(size 1 1)
					(thickness 0.15)
				)
			)
		)
		(property "License" "Apache-2.0"
			(at 0 0 0)
			(layer "F.Fab")
			(hide yes)
			(effects
				(font
					(size 1 1)
					(thickness 0.15)
				)
			)
		)
		(property "MPN" "CR0402-FX-1002GLF"
			(at 0 0 0)
			(layer "F.Fab")
			(hide yes)
			(effects
				(font
					(size 1 1)
					(thickness 0.15)
				)
			)
		)
		(property "Manufacturer" "Bourns"
			(at 0 0 0)
			(layer "F.Fab")
			(hide yes)
			(effects
				(font
					(size 1 1)
					(thickness 0.15)
				)
			)
		)
		(property "Tolerance" "1%"
			(at 0 0 0)
			(layer "F.Fab")
			(hide yes)
			(effects
				(font
					(size 1 1)
					(thickness 0.15)
				)
			)
		)
		(property "Val" "10k"
			(at 0 0 0)
			(layer "F.Fab")
			(hide yes)
			(effects
				(font
					(size 1 1)
					(thickness 0.15)
				)
			)
		)
		(sheetname "/Power/")
		(sheetfile "power.kicad_sch")
		(attr smd)
		(fp_rect
			(start -0.925 -0.47)
			(end 0.925 0.47)
			(stroke
				(width 0.05)
				(type default)
			)
			(fill no)
			(layer "F.CrtYd")
		)
		(fp_rect
			(start -0.5 -0.25)
			(end 0.5 0.25)
			(stroke
				(width 0.15)
				(type solid)
			)
			(fill no)
			(layer "F.Fab")
		)
		(pad "1" smd roundrect
			(at -0.48 0)
			(size 0.59 0.64)
			(layers "F.Cu" "F.Mask" "F.Paste")
			(roundrect_rratio 0.25)
			(net 69 "/Power/EN_1V8")
			(pintype "passive")
		)
		(pad "2" smd roundrect
			(at 0.48 0)
			(size 0.59 0.64)
			(layers "F.Cu" "F.Mask" "F.Paste")
			(roundrect_rratio 0.25)
			(net 4 "+12V")
			(pintype "passive")
		)
	)
	(footprint "antmicro-footprints:R_0402_1005Metric"
		(layer "F.Cu")
		(at 167.386 59.817 90)
		(descr "Resistor SMD 0402")
		(tags "resistor SMD 0402")
		(property "Reference" "R5"
			(at -2.286 0.381 90)
			(layer "F.SilkS")
			(effects
				(font
					(size 0.7 0.7)
					(thickness 0.15)
				)
				(justify left bottom)
			)
		)
		(property "Value" "R_0R_0402"
			(at -1.011843 1.772047 90)
			(layer "F.Fab")
			(effects
				(font
					(size 0.7 0.7)
					(thickness 0.15)
				)
				(justify left bottom)
			)
		)
		(property "Datasheet" "https://industrial.panasonic.com/cdbs/www-data/pdf/RDA0000/AOA0000C301.pdf"
			(at 0 0 90)
			(layer "F.Fab")
			(hide yes)
			(effects
				(font
					(size 1.27 1.27)
					(thickness 0.15)
				)
			)
		)
		(property "Description" "SMD Chip Resistor, Jumper, 0 ohm, 100 mW, 0402 [1005 Metric], Thick Film, General Purpose"
			(at 0 0 90)
			(layer "F.Fab")
			(hide yes)
			(effects
				(font
					(size 1.27 1.27)
					(thickness 0.15)
				)
			)
		)
		(property "Author" "Antmicro"
			(at 227.203 -107.569 0)
			(layer "F.Fab")
			(hide yes)
			(effects
				(font
					(size 1 1)
					(thickness 0.15)
				)
			)
		)
		(property "Current" "1A"
			(at 227.203 -107.569 0)
			(layer "F.Fab")
			(hide yes)
			(effects
				(font
					(size 1 1)
					(thickness 0.15)
				)
			)
		)
		(property "License" "Apache-2.0"
			(at 227.203 -107.569 0)
			(layer "F.Fab")
			(hide yes)
			(effects
				(font
					(size 1 1)
					(thickness 0.15)
				)
			)
		)
		(property "MPN" "ERJ2GE0R00X"
			(at 227.203 -107.569 0)
			(layer "F.Fab")
			(hide yes)
			(effects
				(font
					(size 1 1)
					(thickness 0.15)
				)
			)
		)
		(property "Manufacturer" "Panasonic"
			(at 227.203 -107.569 0)
			(layer "F.Fab")
			(hide yes)
			(effects
				(font
					(size 1 1)
					(thickness 0.15)
				)
			)
		)
		(property "Tolerance" ""
			(at 227.203 -107.569 0)
			(layer "F.Fab")
			(hide yes)
			(effects
				(font
					(size 1 1)
					(thickness 0.15)
				)
			)
		)
		(property "Val" "0R"
			(at 227.203 -107.569 0)
			(layer "F.Fab")
			(hide yes)
			(effects
				(font
					(size 1 1)
					(thickness 0.15)
				)
			)
		)
		(sheetname "/Connectors/")
		(sheetfile "connectors.kicad_sch")
		(attr smd)
		(fp_rect
			(start -0.925 -0.47)
			(end 0.925 0.47)
			(stroke
				(width 0.05)
				(type default)
			)
			(fill no)
			(layer "F.CrtYd")
		)
		(fp_rect
			(start -0.5 -0.25)
			(end 0.5 0.25)
			(stroke
				(width 0.15)
				(type solid)
			)
			(fill no)
			(layer "F.Fab")
		)
		(pad "1" smd roundrect
			(at -0.48 0 90)
			(size 0.59 0.64)
			(layers "F.Cu" "F.Mask" "F.Paste")
			(roundrect_rratio 0.25)
			(net 82 "/Connectors/MFP2")
			(pintype "passive")
		)
		(pad "2" smd roundrect
			(at 0.48 0 90)
			(size 0.59 0.64)
			(layers "F.Cu" "F.Mask" "F.Paste")
			(roundrect_rratio 0.25)
			(net 132 "Net-(U2-Y)")
			(pintype "passive")
		)
	)
)
